#ISCELL
  mstr_misc dns *
  *
#ISCELL
  pure_quanta quanta_title_block_c *
  *
#ISCELL
  pure_quanta_power universal_gnd *
  page167_i1
#CELL
  pure_quanta q_inductor *
  page167_i10
#ISCELL
  pure_quanta_power universal_gnd *
  page167_i11
#CELL
  pure_quanta q_cap *
  page167_i12
#CELL
  pure_quanta q_cap *
  page167_i13
#ISCELL
  pure_quanta_power universal_gnd *
  page167_i14
#CELL
  pure_quanta q_res *
  page167_i15
#ISCELL
  pure_quanta_power universal_gnd *
  page167_i16
#CELL
  pure_quanta q_res *
  page167_i17
#ISCELL
  pure_quanta_power universal_gnd *
  page167_i18
#CELL
  pure_quanta q_cap *
  page167_i19
#CELL
  pure_quanta q_cap *
  page167_i2
#ISCELL
  pure_quanta_power universal_gnd *
  page167_i20
#ISCELL
  pure_quanta_power universal_gnd *
  page167_i21
#ISCELL
  pure_quanta_power universal_gnd *
  page167_i22
#CELL
  pure_quanta q_res *
  page167_i23
#CELL
  pure_quanta q_cap *
  page167_i24
#CELL
  pure_quanta q_res *
  page167_i25
#CELL
  pure_quanta q_cap *
  page167_i27
#CELL
  pure_quanta q_cap *
  page167_i28
#CELL
  pure_quanta q_cap *
  page167_i29
#ISCELL
  standard offpage *
  page167_i3
#CELL
  pure_quanta q_cap *
  page167_i30
#CELL
  pure_quanta q_res *
  page167_i31
#ISCELL
  pure_quanta_power universal_power *
  page167_i32
#CELL
  pure_quanta q_res *
  page167_i33
#ISCELL
  pure_quanta_power universal_gnd *
  page167_i34
#CELL
  pure_quanta q_cap *
  page167_i35
#CELL
  pure_quanta q_cap *
  page167_i36
#CELL
  pure_quanta q_cap *
  page167_i37
#ISCELL
  pure_quanta_power universal_power *
  page167_i38
#ISCELL
  standard offpage *
  page167_i39
#ISCELL
  pure_quanta_power universal_power *
  page167_i4
#CELL
  pure_quanta q_cap *
  page167_i40
#CELL
  pure_quanta mpq8633aglec807z *
  page167_i41
#ISCELL
  pure_quanta_power universal_gnd *
  page167_i42
#CELL
  pure_quanta q_cap *
  page167_i43
#CELL
  pure_quanta q_cap *
  page167_i44
#CELL
  pure_quanta q_cap *
  page167_i45
#CELL
  pure_quanta q_res *
  page167_i46
#CELL
  pure_quanta q_inductor *
  page167_i47
#CELL
  pure_quanta q_cap *
  page167_i5
#ISCELL
  pure_quanta_power universal_gnd *
  page167_i6
#ISCELL
  pure_quanta_power universal_gnd *
  page167_i7
#CELL
  pure_quanta q_cap *
  page167_i8
#ISCELL
  pure_quanta_power universal_power *
  page167_i9
